(kicad_pcb
	(version 20260206)
	(generator "pcbnew")
	(generator_version "10.0")
	(general
		(thickness 1.6)
		(legacy_teardrops no)
	)
	(paper "A4")
	(title_block
		(title "03242023_DA0F0TMBIJ0_F0T_Motherboard_J_brd_V01_OCP.brd")
		(comment 1 "Grand Teton / footprints 908-911 of 6105")
	)
	(layers
		(0 "F.Cu" signal "TOP")
		(4 "In1.Cu" signal "GND")
		(6 "In2.Cu" signal "IN1")
		(8 "In3.Cu" signal "GND1")
		(10 "In4.Cu" signal "IN2")
		(12 "In5.Cu" signal "GND2")
		(14 "In6.Cu" signal "IN3")
		(16 "In7.Cu" signal "GND3")
		(18 "In8.Cu" signal "VCC")
		(20 "In9.Cu" signal "VCC1")
		(22 "In10.Cu" signal "GND4")
		(24 "In11.Cu" signal "IN4")
		(26 "In12.Cu" signal "GND5")
		(28 "In13.Cu" signal "IN5")
		(30 "In14.Cu" signal "GND6")
		(32 "In15.Cu" signal "IN6")
		(34 "In16.Cu" signal "GND7")
		(2 "B.Cu" signal "BOTTOM")
		(9 "F.Adhes" user "F.Adhesive")
		(11 "B.Adhes" user "B.Adhesive")
		(13 "F.Paste" user "Package Geometry/Pastemask Top")
		(15 "B.Paste" user "Package Geometry/Pastemask Bottom")
		(5 "F.SilkS" user "Ref Des/Silkscreen Top")
		(7 "B.SilkS" user "Ref Des/Silkscreen Bottom")
		(1 "F.Mask" user "Board Geometry/Soldermask Top")
		(3 "B.Mask" user "Board Geometry/Soldermask Bottom")
		(17 "Dwgs.User" user "User.Drawings")
		(19 "Cmts.User" user "User.Comments")
		(21 "Eco1.User" user "User.Eco1")
		(23 "Eco2.User" user "User.Eco2")
		(25 "Edge.Cuts" user "Board Geometry/Outline")
		(27 "Margin" user)
		(31 "F.CrtYd" user "Package Geometry/Place Bound Top")
		(29 "B.CrtYd" user "Package Geometry/Place Bound Bottom")
		(35 "F.Fab" user "Ref Des/Assembly Top")
		(33 "B.Fab" user "Ref Des/Assembly Bottom")
	)
	(footprint ""
		(layer "F.Cu")
		(at 365.2012 -411.5562)
		(property "Reference" "R4799"
			(at 0 0 0)
			(layer "F.SilkS")
			(hide yes)
			(effects
				(font
					(size 1.27 1.27)
				)
			)
		)
		(property "Value" ""
			(at 0 0 0)
			(layer "F.Fab")
			(effects
				(font
					(size 1.27 1.27)
				)
			)
		)
		(duplicate_pad_numbers_are_jumpers no)
		(fp_line
			(start -0.7874 -0.4064)
			(end 0.7874 -0.4064)
			(stroke
				(width 0.1524)
				(type default)
			)
			(layer "F.SilkS")
		)
		(fp_line
			(start -0.7874 0.4064)
			(end -0.7874 -0.4064)
			(stroke
				(width 0.1524)
				(type default)
			)
			(layer "F.SilkS")
		)
		(fp_line
			(start 0.7874 -0.4064)
			(end 0.7874 0.4064)
			(stroke
				(width 0.1524)
				(type default)
			)
			(layer "F.SilkS")
		)
		(fp_line
			(start 0.7874 0.4064)
			(end -0.7874 0.4064)
			(stroke
				(width 0.1524)
				(type default)
			)
			(layer "F.SilkS")
		)
		(fp_line
			(start -0.67945 -0.305054)
			(end -0.12065 -0.305054)
			(stroke
				(width 0.1)
				(type default)
			)
			(layer "F.Fab")
		)
		(fp_line
			(start -0.67945 0.3048)
			(end -0.67945 -0.305054)
			(stroke
				(width 0.1)
				(type default)
			)
			(layer "F.Fab")
		)
		(fp_line
			(start -0.12065 -0.305054)
			(end -0.12065 -0.2794)
			(stroke
				(width 0.1)
				(type default)
			)
			(layer "F.Fab")
		)
		(fp_line
			(start -0.12065 -0.2794)
			(end 0.12065 -0.2794)
			(stroke
				(width 0.1)
				(type default)
			)
			(layer "F.Fab")
		)
		(fp_line
			(start -0.12065 0.2794)
			(end -0.12065 0.3048)
			(stroke
				(width 0.1)
				(type default)
			)
			(layer "F.Fab")
		)
		(fp_line
			(start -0.12065 0.3048)
			(end -0.67945 0.3048)
			(stroke
				(width 0.1)
				(type default)
			)
			(layer "F.Fab")
		)
		(fp_line
			(start 0.120396 0.2794)
			(end -0.12065 0.2794)
			(stroke
				(width 0.1)
				(type default)
			)
			(layer "F.Fab")
		)
		(fp_line
			(start 0.120396 0.3048)
			(end 0.120396 0.2794)
			(stroke
				(width 0.1)
				(type default)
			)
			(layer "F.Fab")
		)
		(fp_line
			(start 0.12065 -0.3048)
			(end 0.67945 -0.3048)
			(stroke
				(width 0.1)
				(type default)
			)
			(layer "F.Fab")
		)
		(fp_line
			(start 0.12065 -0.2794)
			(end 0.12065 -0.3048)
			(stroke
				(width 0.1)
				(type default)
			)
			(layer "F.Fab")
		)
		(fp_line
			(start 0.67945 -0.3048)
			(end 0.67945 0.3048)
			(stroke
				(width 0.1)
				(type default)
			)
			(layer "F.Fab")
		)
		(fp_line
			(start 0.67945 0.3048)
			(end 0.120396 0.3048)
			(stroke
				(width 0.1)
				(type default)
			)
			(layer "F.Fab")
		)
		(pad "1" smd circle
			(at -0.40005 0)
			(size 0 0)
			(layers "F.Cu" "F.Mask" "F.Paste")
			(net "PRSNT_CABLE_GPU_A3_N")
		)
		(pad "2" smd circle
			(at 0.40005 0)
			(size 0 0)
			(layers "F.Cu" "F.Mask" "F.Paste")
			(net "GND")
		)
	)
	(footprint ""
		(layer "F.Cu")
		(at 235.51388 -256.123948 -90)
		(property "Reference" "R3341"
			(at 0 0 270)
			(layer "F.SilkS")
			(hide yes)
			(effects
				(font
					(size 1.27 1.27)
				)
			)
		)
		(property "Value" ""
			(at 0 0 270)
			(layer "F.Fab")
			(effects
				(font
					(size 1.27 1.27)
				)
			)
		)
		(duplicate_pad_numbers_are_jumpers no)
		(fp_line
			(start -0.7874 0.4064)
			(end -0.7874 -0.4064)
			(stroke
				(width 0.1524)
				(type default)
			)
			(layer "F.SilkS")
		)
		(fp_line
			(start 0.7874 0.4064)
			(end -0.7874 0.4064)
			(stroke
				(width 0.1524)
				(type default)
			)
			(layer "F.SilkS")
		)
		(fp_line
			(start -0.7874 -0.4064)
			(end 0.7874 -0.4064)
			(stroke
				(width 0.1524)
				(type default)
			)
			(layer "F.SilkS")
		)
		(fp_line
			(start 0.7874 -0.4064)
			(end 0.7874 0.4064)
			(stroke
				(width 0.1524)
				(type default)
			)
			(layer "F.SilkS")
		)
		(fp_line
			(start -0.67945 0.3048)
			(end -0.67945 -0.305054)
			(stroke
				(width 0.1)
				(type default)
			)
			(layer "F.Fab")
		)
		(fp_line
			(start -0.12065 0.3048)
			(end -0.67945 0.3048)
			(stroke
				(width 0.1)
				(type default)
			)
			(layer "F.Fab")
		)
		(fp_line
			(start 0.120396 0.3048)
			(end 0.120396 0.2794)
			(stroke
				(width 0.1)
				(type default)
			)
			(layer "F.Fab")
		)
		(fp_line
			(start 0.67945 0.3048)
			(end 0.120396 0.3048)
			(stroke
				(width 0.1)
				(type default)
			)
			(layer "F.Fab")
		)
		(fp_line
			(start -0.12065 0.2794)
			(end -0.12065 0.3048)
			(stroke
				(width 0.1)
				(type default)
			)
			(layer "F.Fab")
		)
		(fp_line
			(start 0.120396 0.2794)
			(end -0.12065 0.2794)
			(stroke
				(width 0.1)
				(type default)
			)
			(layer "F.Fab")
		)
		(fp_line
			(start -0.12065 -0.2794)
			(end 0.12065 -0.2794)
			(stroke
				(width 0.1)
				(type default)
			)
			(layer "F.Fab")
		)
		(fp_line
			(start 0.12065 -0.2794)
			(end 0.12065 -0.3048)
			(stroke
				(width 0.1)
				(type default)
			)
			(layer "F.Fab")
		)
		(fp_line
			(start 0.12065 -0.3048)
			(end 0.67945 -0.3048)
			(stroke
				(width 0.1)
				(type default)
			)
			(layer "F.Fab")
		)
		(fp_line
			(start 0.67945 -0.3048)
			(end 0.67945 0.3048)
			(stroke
				(width 0.1)
				(type default)
			)
			(layer "F.Fab")
		)
		(fp_line
			(start -0.67945 -0.305054)
			(end -0.12065 -0.305054)
			(stroke
				(width 0.1)
				(type default)
			)
			(layer "F.Fab")
		)
		(fp_line
			(start -0.12065 -0.305054)
			(end -0.12065 -0.2794)
			(stroke
				(width 0.1)
				(type default)
			)
			(layer "F.Fab")
		)
		(pad "1" smd circle
			(at -0.40005 0 270)
			(size 0 0)
			(layers "F.Cu" "F.Mask" "F.Paste")
			(net "SMB_HOST_CLK_3V3AUX_SDA")
		)
		(pad "2" smd circle
			(at 0.40005 0 270)
			(size 0 0)
			(layers "F.Cu" "F.Mask" "F.Paste")
			(net "SMB_HOST_CLK_GEN2_3V3AUX_SDA")
		)
	)
	(footprint ""
		(layer "F.Cu")
		(at 105.3084 -252.956568 -90)
		(property "Reference" "C266"
			(at 0 0 270)
			(layer "F.SilkS")
			(hide yes)
			(effects
				(font
					(size 1.27 1.27)
				)
			)
		)
		(property "Value" ""
			(at 0 0 270)
			(layer "F.Fab")
			(effects
				(font
					(size 1.27 1.27)
				)
			)
		)
		(duplicate_pad_numbers_are_jumpers no)
		(fp_line
			(start -0.7874 0.4064)
			(end -0.7874 -0.4064)
			(stroke
				(width 0.1524)
				(type default)
			)
			(layer "F.SilkS")
		)
		(fp_line
			(start 0.7874 0.4064)
			(end -0.7874 0.4064)
			(stroke
				(width 0.1524)
				(type default)
			)
			(layer "F.SilkS")
		)
		(fp_line
			(start -0.7874 -0.4064)
			(end 0.7874 -0.4064)
			(stroke
				(width 0.1524)
				(type default)
			)
			(layer "F.SilkS")
		)
		(fp_line
			(start 0.7874 -0.4064)
			(end 0.7874 0.4064)
			(stroke
				(width 0.1524)
				(type default)
			)
			(layer "F.SilkS")
		)
		(fp_line
			(start -0.67945 0.3048)
			(end -0.67945 -0.305054)
			(stroke
				(width 0.1)
				(type default)
			)
			(layer "F.Fab")
		)
		(fp_line
			(start -0.12065 0.3048)
			(end -0.67945 0.3048)
			(stroke
				(width 0.1)
				(type default)
			)
			(layer "F.Fab")
		)
		(fp_line
			(start 0.120396 0.3048)
			(end 0.120396 0.2794)
			(stroke
				(width 0.1)
				(type default)
			)
			(layer "F.Fab")
		)
		(fp_line
			(start 0.67945 0.3048)
			(end 0.120396 0.3048)
			(stroke
				(width 0.1)
				(type default)
			)
			(layer "F.Fab")
		)
		(fp_line
			(start -0.12065 0.2794)
			(end -0.12065 0.3048)
			(stroke
				(width 0.1)
				(type default)
			)
			(layer "F.Fab")
		)
		(fp_line
			(start 0.120396 0.2794)
			(end -0.12065 0.2794)
			(stroke
				(width 0.1)
				(type default)
			)
			(layer "F.Fab")
		)
		(fp_line
			(start -0.12065 -0.2794)
			(end 0.12065 -0.2794)
			(stroke
				(width 0.1)
				(type default)
			)
			(layer "F.Fab")
		)
		(fp_line
			(start 0.12065 -0.2794)
			(end 0.12065 -0.3048)
			(stroke
				(width 0.1)
				(type default)
			)
			(layer "F.Fab")
		)
		(fp_line
			(start 0.12065 -0.3048)
			(end 0.67945 -0.3048)
			(stroke
				(width 0.1)
				(type default)
			)
			(layer "F.Fab")
		)
		(fp_line
			(start 0.67945 -0.3048)
			(end 0.67945 0.3048)
			(stroke
				(width 0.1)
				(type default)
			)
			(layer "F.Fab")
		)
		(fp_line
			(start -0.67945 -0.305054)
			(end -0.12065 -0.305054)
			(stroke
				(width 0.1)
				(type default)
			)
			(layer "F.Fab")
		)
		(fp_line
			(start -0.12065 -0.305054)
			(end -0.12065 -0.2794)
			(stroke
				(width 0.1)
				(type default)
			)
			(layer "F.Fab")
		)
		(pad "1" smd circle
			(at -0.40005 0 270)
			(size 0 0)
			(layers "F.Cu" "F.Mask" "F.Paste")
			(net "PVCCIN_CPU1")
		)
		(pad "2" smd circle
			(at 0.40005 0 270)
			(size 0 0)
			(layers "F.Cu" "F.Mask" "F.Paste")
			(net "GND")
		)
	)
	(footprint ""
		(layer "F.Cu")
		(at 369.419124 -333.716122)
		(property "Reference" "PU10_P0_4"
			(at 3.442716 -12.403836 0)
			(unlocked yes)
			(layer "F.SilkS")
			(effects
				(font
					(size 0.7874 0.5842)
					(thickness 0.1524)
				)
				(justify left)
			)
		)
		(property "Value" ""
			(at 0 0 0)
			(layer "F.Fab")
			(effects
				(font
					(size 1.27 1.27)
				)
			)
		)
		(duplicate_pad_numbers_are_jumpers no)
		(fp_line
			(start -2.500122 -2.999994)
			(end -2.24409 -2.999994)
			(stroke
				(width 0.1524)
				(type default)
			)
			(layer "F.SilkS")
		)
		(fp_line
			(start -2.500122 -2.529078)
			(end -2.500122 -2.999994)
			(stroke
				(width 0.1524)
				(type default)
			)
			(layer "F.SilkS")
		)
		(fp_line
			(start -2.500122 0.6604)
			(end -2.500122 0.229108)
			(stroke
				(width 0.1524)
				(type default)
			)
			(layer "F.SilkS")
		)
		(fp_line
			(start -2.500122 2.999994)
			(end -2.500122 2.339594)
			(stroke
				(width 0.1524)
				(type default)
			)
			(layer "F.SilkS")
		)
		(fp_line
			(start -2.2987 2.999994)
			(end -2.500122 2.999994)
			(stroke
				(width 0.1524)
				(type default)
			)
			(layer "F.SilkS")
		)
		(fp_line
			(start 2.31394 -2.999994)
			(end 2.500122 -2.999994)
			(stroke
				(width 0.1524)
				(type default)
			)
			(layer "F.SilkS")
		)
		(fp_line
			(start 2.500122 -2.999994)
			(end 2.500122 -2.44348)
			(stroke
				(width 0.1524)
				(type default)
			)
			(layer "F.SilkS")
		)
		(fp_line
			(start 2.500122 2.339594)
			(end 2.500122 2.999994)
			(stroke
				(width 0.1524)
				(type default)
			)
			(layer "F.SilkS")
		)
		(fp_line
			(start 2.500122 2.999994)
			(end 2.2987 2.999994)
			(stroke
				(width 0.1524)
				(type default)
			)
			(layer "F.SilkS")
		)
		(fp_poly
			(pts
				(xy -2.168652 -3.624834) (xy -2.676652 -2.608834) (xy -3.184652 -3.624834)
			)
			(stroke
				(width 0)
				(type default)
			)
			(fill yes)
			(layer "F.SilkS")
		)
		(fp_line
			(start -2.500122 -2.999994)
			(end 2.500122 -2.999994)
			(stroke
				(width 0.1)
				(type default)
			)
			(layer "F.Fab")
		)
		(fp_line
			(start -2.500122 2.999994)
			(end -2.500122 -2.999994)
			(stroke
				(width 0.1)
				(type default)
			)
			(layer "F.Fab")
		)
		(fp_line
			(start 2.500122 -2.999994)
			(end 2.500122 2.999994)
			(stroke
				(width 0.1)
				(type default)
			)
			(layer "F.Fab")
		)
		(fp_line
			(start 2.500122 2.999994)
			(end -2.500122 2.999994)
			(stroke
				(width 0.1)
				(type default)
			)
			(layer "F.Fab")
		)
		(fp_poly
			(pts
				(xy -4.218432 -2.783078) (xy -4.218432 -1.767078) (xy -3.202432 -2.275078)
			)
			(stroke
				(width 0)
				(type default)
			)
			(fill yes)
			(layer "F.Fab")
		)
		(pad "1" smd rect
			(at -2.400046 -2.275078 90)
			(size 0.2286 0.6096)
			(layers "F.Cu" "F.Mask" "F.Paste")
			(net "PVCCIN_CPU0_VOS4")
		)
		(pad "2" smd rect
			(at -2.400046 -1.82499 90)
			(size 0.2286 0.6096)
			(layers "F.Cu" "F.Mask" "F.Paste")
			(net "GND")
		)
		(pad "3" smd rect
			(at -2.400046 -1.374902 90)
			(size 0.2286 0.6096)
			(layers "F.Cu" "F.Mask" "F.Paste")
			(net "PVCCIN_CPU0_VDD4")
		)
		(pad "4" smd rect
			(at -2.400046 -0.925068 90)
			(size 0.2286 0.6096)
			(layers "F.Cu" "F.Mask" "F.Paste")
			(net "PVCCIN_CPU0_PVCC")
		)
		(pad "5" smd rect
			(at -2.400046 -0.47498 90)
			(size 0.2286 0.6096)
			(layers "F.Cu" "F.Mask" "F.Paste")
			(net "GND")
		)
		(pad "6" smd rect
			(at -2.400046 -0.024892 90)
			(size 0.2286 0.6096)
			(layers "F.Cu" "F.Mask" "F.Paste")
			(net "Net_8553")
		)
		(pad "7_9-20_24" smd circle
			(at 0 1.150112 90)
			(size 0 0)
			(layers "F.Cu" "F.Mask" "F.Paste")
			(net "GND")
		)
		(pad "10_19" smd rect
			(at 0 2.899918 90)
			(size 0.6096 4.318)
			(layers "F.Cu" "F.Mask" "F.Paste")
			(net "SW_PVCCIN_CPU0_SW4")
		)
		(pad "25_29" smd rect
			(at 1.549908 -1.279906 270)
			(size 2.0574 2.3114)
			(layers "F.Cu" "F.Mask" "F.Paste")
			(net "SW_P12V_PVCCIN_CPU0_FLT")
		)
		(pad "30" smd rect
			(at 2.05994 -2.899918)
			(size 0.2286 0.6096)
			(layers "F.Cu" "F.Mask" "F.Paste")
			(net "SW_P12V_PVCCIN_CPU0_FLT")
		)
		(pad "31" smd rect
			(at 1.610106 -2.899918)
			(size 0.2286 0.6096)
			(layers "F.Cu" "F.Mask" "F.Paste")
			(net "Net_8554")
		)
		(pad "32" smd rect
			(at 1.160018 -2.899918)
			(size 0.2286 0.6096)
			(layers "F.Cu" "F.Mask" "F.Paste")
			(net "SW_PVCCIN_CPU0_BOOTR4")
		)
		(pad "33" smd rect
			(at 0.70993 -2.899918)
			(size 0.2286 0.6096)
			(layers "F.Cu" "F.Mask" "F.Paste")
			(net "SW_PVCCIN_CPU0_BOOT4")
		)
		(pad "34" smd rect
			(at 0.260096 -2.899918)
			(size 0.2286 0.6096)
			(layers "F.Cu" "F.Mask" "F.Paste")
			(net "PVCCIN_CPU0_PWM4")
		)
		(pad "35" smd rect
			(at -0.189992 -2.899918)
			(size 0.2286 0.6096)
			(layers "F.Cu" "F.Mask" "F.Paste")
			(net "PVCCIN_CPU0_VDD4")
		)
		(pad "36" smd rect
			(at -0.64008 -2.899918)
			(size 0.2286 0.6096)
			(layers "F.Cu" "F.Mask" "F.Paste")
			(net "PVCCIN_CPU0_ATSEN")
		)
		(pad "37" smd rect
			(at -1.089914 -2.899918)
			(size 0.2286 0.6096)
			(layers "F.Cu" "F.Mask" "F.Paste")
			(net "PVCCIN_CPU0_LSET4")
		)
		(pad "38" smd rect
			(at -1.540002 -2.899918)
			(size 0.2286 0.6096)
			(layers "F.Cu" "F.Mask" "F.Paste")
			(net "PVCCIN_CPU0_IMON4")
		)
		(pad "39" smd rect
			(at -1.99009 -2.899918)
			(size 0.2286 0.6096)
			(layers "F.Cu" "F.Mask" "F.Paste")
			(net "PVCCIN_CPU0_VREF")
		)
		(pad "40" smd rect
			(at -0.87503 -1.27508)
			(size 1.7526 1.9558)
			(layers "F.Cu" "F.Mask" "F.Paste")
			(net "GND")
		)
		(pad "41" smd rect
			(at -1.525016 0.249936 270)
			(size 0.3048 0.4572)
			(layers "F.Cu" "F.Mask" "F.Paste")
			(net "Net_8552")
		)
		(zone
			(layer "F.Cu")
			(hatch none 0.5)
			(connect_pads
				(clearance 0)
			)
			(min_thickness 0.25)
			(keepout
				(tracks not_allowed)
				(vias allowed)
				(pads allowed)
				(copperpour not_allowed)
				(footprints allowed)
			)
			(placement
				(enabled no)
				(sheetname "")
			)
			(fill
				(thermal_gap 0.5)
				(thermal_bridge_width 0.5)
				(island_removal_mode 0)
			)
			(polygon
				(pts
					(xy 368.173508 -333.652368) (xy 368.468402 -333.652368) (xy 368.468402 -332.966822) (xy 366.919002 -332.966822)
					(xy 366.919002 -333.423514) (xy 367.614708 -333.423514) (xy 367.614708 -333.262986) (xy 368.173508 -333.262986)
				)
			)
		)
		(zone
			(layer "F.Cu")
			(hatch none 0.5)
			(connect_pads
				(clearance 0)
			)
			(min_thickness 0.25)
			(keepout
				(tracks not_allowed)
				(vias allowed)
				(pads allowed)
				(copperpour not_allowed)
				(footprints allowed)
			)
			(placement
				(enabled no)
				(sheetname "")
			)
			(fill
				(thermal_gap 0.5)
				(thermal_bridge_width 0.5)
				(island_removal_mode 0)
			)
			(polygon
				(pts
					(xy 366.919002 -330.716128) (xy 366.919002 -331.465428) (xy 371.919246 -331.465428) (xy 371.919246 -330.716128)
					(xy 371.6909 -330.716128) (xy 371.6909 -331.109828) (xy 371.628924 -331.171804) (xy 367.209324 -331.171804)
					(xy 367.209324 -330.716128)
				)
			)
		)
	)
)
